(kicad_pcb
	(version 20260206)
	(generator "pcbnew")
	(generator_version "10.0")
	(general
		(thickness 1.6)
		(legacy_teardrops no)
	)
	(paper "A4")
	(title_block
		(title "Bryce Canyon_R.DPB_16317-1_OCP.brd")
		(comment 1 "Bryce Canyon / footprints 1040-1046 of 2099")
	)
	(layers
		(0 "F.Cu" signal "TOP")
		(4 "In1.Cu" signal "L2GND")
		(6 "In2.Cu" signal "L3")
		(8 "In3.Cu" signal "L4VCC")
		(10 "In4.Cu" signal "L5VCC")
		(12 "In5.Cu" signal "L6")
		(14 "In6.Cu" signal "L7GND")
		(2 "B.Cu" signal "BOTTOM")
		(9 "F.Adhes" user "F.Adhesive")
		(11 "B.Adhes" user "B.Adhesive")
		(13 "F.Paste" user "Package Geometry/Pastemask Top")
		(15 "B.Paste" user "Package Geometry/Pastemask Bottom")
		(5 "F.SilkS" user "Ref Des/Silkscreen Top")
		(7 "B.SilkS" user "Ref Des/Silkscreen Bottom")
		(1 "F.Mask" user "Board Geometry/Soldermask Top")
		(3 "B.Mask" user "Board Geometry/Soldermask Bottom")
		(17 "Dwgs.User" user "User.Drawings")
		(19 "Cmts.User" user "User.Comments")
		(21 "Eco1.User" user "User.Eco1")
		(23 "Eco2.User" user "User.Eco2")
		(25 "Edge.Cuts" user "Board Geometry/Outline")
		(27 "Margin" user)
		(31 "F.CrtYd" user "Package Geometry/Place Bound Top")
		(29 "B.CrtYd" user "Package Geometry/Place Bound Bottom")
		(35 "F.Fab" user "Ref Des/Assembly Top")
		(33 "B.Fab" user "Ref Des/Assembly Bottom")
	)
	(footprint ""
		(layer "F.Cu")
		(at 115.316 -256.286 180)
		(property "Reference" "Q10"
			(at 0 0 180)
			(layer "F.SilkS")
			(hide yes)
			(effects
				(font
					(size 1.27 1.27)
				)
			)
		)
		(property "Value" "AO4406AL-GP"
			(at -3.707384 -1.5367 180)
			(unlocked yes)
			(layer "F.Fab")
			(hide yes)
			(effects
				(font
					(size 1.016 1.016)
					(thickness 0.1524)
				)
			)
		)
		(property "Device Type" "SOIC8H69"
			(at -3.707384 -3.0607 180)
			(unlocked yes)
			(layer "F.Fab")
			(hide yes)
			(effects
				(font
					(size 1.016 1.016)
					(thickness 0.1524)
				)
			)
		)
		(duplicate_pad_numbers_are_jumpers no)
		(fp_line
			(start 2.1336 1.4224)
			(end 2.1336 -1.4224)
			(stroke
				(width 0.1524)
				(type default)
			)
			(layer "F.SilkS")
		)
		(fp_line
			(start 2.1336 -1.4224)
			(end -2.7432 -1.4224)
			(stroke
				(width 0.1524)
				(type default)
			)
			(layer "F.SilkS")
		)
		(fp_line
			(start -2.1844 -0.0508)
			(end -2.7178 0.508)
			(stroke
				(width 0.1524)
				(type default)
			)
			(layer "F.SilkS")
		)
		(fp_line
			(start -2.6289 3.4417)
			(end -2.6289 1.4732)
			(stroke
				(width 0.381)
				(type default)
			)
			(layer "F.SilkS")
		)
		(fp_line
			(start -2.7178 -0.508)
			(end -2.1844 -0.0508)
			(stroke
				(width 0.1524)
				(type default)
			)
			(layer "F.SilkS")
		)
		(fp_line
			(start -2.7432 1.4224)
			(end 2.1336 1.4224)
			(stroke
				(width 0.1524)
				(type default)
			)
			(layer "F.SilkS")
		)
		(fp_line
			(start -2.7432 1.4224)
			(end -2.6416 1.4224)
			(stroke
				(width 0.1524)
				(type default)
			)
			(layer "F.SilkS")
		)
		(fp_line
			(start -2.7432 -1.4224)
			(end -2.7432 1.4224)
			(stroke
				(width 0.1524)
				(type default)
			)
			(layer "F.SilkS")
		)
		(fp_poly
			(pts
				(xy -2.2098 -1.4224) (xy -2.2098 1.4224) (xy 2.2098 1.4224) (xy 2.2098 -1.4224)
			)
			(stroke
				(width 0)
				(type default)
			)
			(fill yes)
			(layer "F.SilkS")
		)
		(fp_rect
			(start -2.450084 2.999994)
			(end 2.450084 -2.999994)
			(stroke
				(width 0)
				(type default)
			)
			(fill no)
			(layer "F.CrtYd")
		)
		(fp_poly
			(pts
				(xy -2.8194 3.6322) (xy -2.8194 -3.6322) (xy 2.8194 -3.6322) (xy 2.8194 1.18364) (xy 2.450084 1.18364)
				(xy 2.450084 -2.999994) (xy -2.450084 -2.999994) (xy -2.450084 2.999994) (xy 2.450084 2.999994)
				(xy 2.450084 1.18618) (xy 2.8194 1.18618) (xy 2.8194 3.6322)
			)
			(stroke
				(width 0)
				(type default)
			)
			(fill no)
			(layer "F.CrtYd")
		)
		(fp_rect
			(start -2.8194 3.6322)
			(end 2.8194 -3.6322)
			(stroke
				(width 0)
				(type default)
			)
			(fill no)
			(layer "F.Fab")
		)
		(pad "1" smd rect
			(at -1.905 2.54 180)
			(size 0.635 1.651)
			(layers "F.Cu" "F.Mask" "F.Paste")
			(net "P5V_HDD3")
		)
		(pad "2" smd rect
			(at -0.635 2.54 180)
			(size 0.635 1.651)
			(layers "F.Cu" "F.Mask" "F.Paste")
			(net "P5V_HDD3")
		)
		(pad "3" smd rect
			(at 0.635 2.54 180)
			(size 0.635 1.651)
			(layers "F.Cu" "F.Mask" "F.Paste")
			(net "P5V_HDD3")
		)
		(pad "4" smd rect
			(at 1.905 2.54 180)
			(size 0.635 1.651)
			(layers "F.Cu" "F.Mask" "F.Paste")
			(net "SW_HDD_P3")
		)
		(pad "5" smd rect
			(at 1.905 -2.54 180)
			(size 0.635 1.651)
			(layers "F.Cu" "F.Mask" "F.Paste")
			(net "P5V_B_1")
		)
		(pad "6" smd rect
			(at 0.635 -2.54 180)
			(size 0.635 1.651)
			(layers "F.Cu" "F.Mask" "F.Paste")
			(net "P5V_B_1")
		)
		(pad "7" smd rect
			(at -0.635 -2.54 180)
			(size 0.635 1.651)
			(layers "F.Cu" "F.Mask" "F.Paste")
			(net "P5V_B_1")
		)
		(pad "8" smd rect
			(at -1.905 -2.54 180)
			(size 0.635 1.651)
			(layers "F.Cu" "F.Mask" "F.Paste")
			(net "P5V_B_1")
		)
	)
	(footprint ""
		(layer "F.Cu")
		(at 207.3148 -199.517 -90)
		(property "Reference" "R29"
			(at 0 0 270)
			(layer "F.SilkS")
			(hide yes)
			(effects
				(font
					(size 1.27 1.27)
				)
			)
		)
		(property "Value" "4K7R2F-GP"
			(at 0.064008 -3.993896 270)
			(unlocked yes)
			(layer "F.Fab")
			(hide yes)
			(effects
				(font
					(size 1.016 1.016)
					(thickness 0.1524)
				)
			)
		)
		(property "Device Type" "R402H16"
			(at 0.064008 -5.517896 270)
			(unlocked yes)
			(layer "F.Fab")
			(hide yes)
			(effects
				(font
					(size 1.016 1.016)
					(thickness 0.1524)
				)
			)
		)
		(duplicate_pad_numbers_are_jumpers no)
		(fp_line
			(start -0.508 -0.9398)
			(end -0.508 0.9398)
			(stroke
				(width 0.1524)
				(type default)
			)
			(layer "F.SilkS")
		)
		(fp_line
			(start 0.508 -0.9398)
			(end -0.508 -0.9398)
			(stroke
				(width 0.1524)
				(type default)
			)
			(layer "F.SilkS")
		)
		(fp_rect
			(start -0.508 0.9398)
			(end 0.508 -0.9398)
			(stroke
				(width 0)
				(type default)
			)
			(fill no)
			(layer "F.CrtYd")
		)
		(fp_rect
			(start -0.508 0.9398)
			(end 0.508 -0.9398)
			(stroke
				(width 0)
				(type default)
			)
			(fill no)
			(layer "F.Fab")
		)
		(pad "1" smd custom
			(at 0 -0.4445 270)
			(size 0.1397 0.1397)
			(layers "F.Cu" "F.Mask" "F.Paste")
			(net "IO_EXP2_HDD_FAULT_INT_N")
			(options
				(clearance outline)
				(anchor circle)
			)
			(primitives
				(gr_poly
					(pts
						(arc
							(start -0.1778 -0.2794)
							(mid -0.249642 -0.249642)
							(end -0.2794 -0.1778)
						)
						(arc
							(start -0.2794 0.1778)
							(mid -0.249642 0.249642)
							(end -0.1778 0.2794)
						)
						(arc
							(start 0.1778 0.2794)
							(mid 0.249642 0.249642)
							(end 0.2794 0.1778)
						)
						(arc
							(start 0.2794 -0.1778)
							(mid 0.249642 -0.249642)
							(end 0.1778 -0.2794)
						)
					)
					(width 0)
					(fill yes)
				)
			)
		)
		(pad "2" smd custom
			(at 0 0.4445 270)
			(size 0.1397 0.1397)
			(layers "F.Cu" "F.Mask" "F.Paste")
			(net "P3V3_STBY_B")
			(options
				(clearance outline)
				(anchor circle)
			)
			(primitives
				(gr_poly
					(pts
						(arc
							(start -0.1778 -0.2794)
							(mid -0.249642 -0.249642)
							(end -0.2794 -0.1778)
						)
						(arc
							(start -0.2794 0.1778)
							(mid -0.249642 0.249642)
							(end -0.1778 0.2794)
						)
						(arc
							(start 0.1778 0.2794)
							(mid 0.249642 0.249642)
							(end 0.2794 0.1778)
						)
						(arc
							(start 0.2794 -0.1778)
							(mid 0.249642 -0.249642)
							(end 0.1778 -0.2794)
						)
					)
					(width 0)
					(fill yes)
				)
			)
		)
	)
	(footprint ""
		(layer "F.Cu")
		(at 66.802 -148.082 -90)
		(property "Reference" "R369"
			(at 0 0 270)
			(layer "F.SilkS")
			(hide yes)
			(effects
				(font
					(size 1.27 1.27)
				)
			)
		)
		(property "Value" "10KR2F-2-GP"
			(at 0.064008 -3.993896 270)
			(unlocked yes)
			(layer "F.Fab")
			(hide yes)
			(effects
				(font
					(size 1.016 1.016)
					(thickness 0.1524)
				)
			)
		)
		(property "Device Type" "R402H16"
			(at 0.064008 -5.517896 270)
			(unlocked yes)
			(layer "F.Fab")
			(hide yes)
			(effects
				(font
					(size 1.016 1.016)
					(thickness 0.1524)
				)
			)
		)
		(duplicate_pad_numbers_are_jumpers no)
		(fp_line
			(start -0.508 -0.9398)
			(end -0.508 0.9398)
			(stroke
				(width 0.1524)
				(type default)
			)
			(layer "F.SilkS")
		)
		(fp_line
			(start 0.508 -0.9398)
			(end -0.508 -0.9398)
			(stroke
				(width 0.1524)
				(type default)
			)
			(layer "F.SilkS")
		)
		(fp_rect
			(start -0.508 0.9398)
			(end 0.508 -0.9398)
			(stroke
				(width 0)
				(type default)
			)
			(fill no)
			(layer "F.CrtYd")
		)
		(fp_rect
			(start -0.508 0.9398)
			(end 0.508 -0.9398)
			(stroke
				(width 0)
				(type default)
			)
			(fill no)
			(layer "F.Fab")
		)
		(pad "1" smd custom
			(at 0 -0.4445 270)
			(size 0.1397 0.1397)
			(layers "F.Cu" "F.Mask" "F.Paste")
			(net "P3V3_STBY_B")
			(options
				(clearance outline)
				(anchor circle)
			)
			(primitives
				(gr_poly
					(pts
						(arc
							(start -0.1778 -0.2794)
							(mid -0.249642 -0.249642)
							(end -0.2794 -0.1778)
						)
						(arc
							(start -0.2794 0.1778)
							(mid -0.249642 0.249642)
							(end -0.1778 0.2794)
						)
						(arc
							(start 0.1778 0.2794)
							(mid 0.249642 0.249642)
							(end 0.2794 0.1778)
						)
						(arc
							(start 0.2794 -0.1778)
							(mid 0.249642 -0.249642)
							(end 0.1778 -0.2794)
						)
					)
					(width 0)
					(fill yes)
				)
			)
		)
		(pad "2" smd custom
			(at 0 0.4445 270)
			(size 0.1397 0.1397)
			(layers "F.Cu" "F.Mask" "F.Paste")
			(net "HDD_PRSNT_13")
			(options
				(clearance outline)
				(anchor circle)
			)
			(primitives
				(gr_poly
					(pts
						(arc
							(start -0.1778 -0.2794)
							(mid -0.249642 -0.249642)
							(end -0.2794 -0.1778)
						)
						(arc
							(start -0.2794 0.1778)
							(mid -0.249642 0.249642)
							(end -0.1778 0.2794)
						)
						(arc
							(start 0.1778 0.2794)
							(mid 0.249642 0.249642)
							(end 0.2794 0.1778)
						)
						(arc
							(start 0.2794 -0.1778)
							(mid 0.249642 -0.249642)
							(end 0.1778 -0.2794)
						)
					)
					(width 0)
					(fill yes)
				)
			)
		)
	)
	(footprint ""
		(layer "F.Cu")
		(at 428.117 -44.958 180)
		(property "Reference" "C465"
			(at 0 0 180)
			(layer "F.SilkS")
			(hide yes)
			(effects
				(font
					(size 1.27 1.27)
				)
			)
		)
		(property "Value" "SC4D7U25V5KX-1-GP"
			(at -0.0762 -6.1214 180)
			(unlocked yes)
			(layer "F.Fab")
			(hide yes)
			(effects
				(font
					(size 1.016 1.016)
					(thickness 0.1524)
				)
			)
		)
		(property "Device Type" "C805H58"
			(at -0.0762 -8.1534 180)
			(unlocked yes)
			(layer "F.Fab")
			(hide yes)
			(effects
				(font
					(size 1.016 1.016)
					(thickness 0.1524)
				)
			)
		)
		(duplicate_pad_numbers_are_jumpers no)
		(fp_line
			(start 0.635 0)
			(end -0.635 0)
			(stroke
				(width 0.508)
				(type default)
			)
			(layer "F.SilkS")
		)
		(fp_rect
			(start -0.9652 1.778)
			(end 0.9652 -1.778)
			(stroke
				(width 0)
				(type default)
			)
			(fill no)
			(layer "F.CrtYd")
		)
		(fp_poly
			(pts
				(xy -0.9652 -1.778) (xy 0.9652 -1.778) (xy 0.9652 1.778) (xy -0.9652 1.778)
			)
			(stroke
				(width 0)
				(type default)
			)
			(fill no)
			(layer "F.Fab")
		)
		(pad "1" smd rect
			(at 0 -0.9652 180)
			(size 1.397 1.143)
			(layers "F.Cu" "F.Mask" "F.Paste")
			(net "P12V_HDD33")
		)
		(pad "2" smd rect
			(at 0 0.9652 180)
			(size 1.397 1.143)
			(layers "F.Cu" "F.Mask" "F.Paste")
			(net "GND")
		)
	)
	(footprint ""
		(layer "F.Cu")
		(at 261.153148 -215.700356 -90)
		(property "Reference" "R164"
			(at 0 0 270)
			(layer "F.SilkS")
			(hide yes)
			(effects
				(font
					(size 1.27 1.27)
				)
			)
		)
		(property "Value" "4K7R2F-GP"
			(at 0.064008 -3.993896 270)
			(unlocked yes)
			(layer "F.Fab")
			(hide yes)
			(effects
				(font
					(size 1.016 1.016)
					(thickness 0.1524)
				)
			)
		)
		(property "Device Type" "R402H16"
			(at 0.064008 -5.517896 270)
			(unlocked yes)
			(layer "F.Fab")
			(hide yes)
			(effects
				(font
					(size 1.016 1.016)
					(thickness 0.1524)
				)
			)
		)
		(duplicate_pad_numbers_are_jumpers no)
		(fp_line
			(start -0.508 -0.9398)
			(end -0.508 0.9398)
			(stroke
				(width 0.1524)
				(type default)
			)
			(layer "F.SilkS")
		)
		(fp_line
			(start 0.508 -0.9398)
			(end -0.508 -0.9398)
			(stroke
				(width 0.1524)
				(type default)
			)
			(layer "F.SilkS")
		)
		(fp_rect
			(start -0.508 0.9398)
			(end 0.508 -0.9398)
			(stroke
				(width 0)
				(type default)
			)
			(fill no)
			(layer "F.CrtYd")
		)
		(fp_rect
			(start -0.508 0.9398)
			(end 0.508 -0.9398)
			(stroke
				(width 0)
				(type default)
			)
			(fill no)
			(layer "F.Fab")
		)
		(pad "1" smd custom
			(at 0 -0.4445 270)
			(size 0.1397 0.1397)
			(layers "F.Cu" "F.Mask" "F.Paste")
			(net "VOL_SEN_ADDR1")
			(options
				(clearance outline)
				(anchor circle)
			)
			(primitives
				(gr_poly
					(pts
						(arc
							(start -0.1778 -0.2794)
							(mid -0.249642 -0.249642)
							(end -0.2794 -0.1778)
						)
						(arc
							(start -0.2794 0.1778)
							(mid -0.249642 0.249642)
							(end -0.1778 0.2794)
						)
						(arc
							(start 0.1778 0.2794)
							(mid 0.249642 0.249642)
							(end 0.2794 0.1778)
						)
						(arc
							(start 0.2794 -0.1778)
							(mid 0.249642 -0.249642)
							(end 0.1778 -0.2794)
						)
					)
					(width 0)
					(fill yes)
				)
			)
		)
		(pad "2" smd custom
			(at 0 0.4445 270)
			(size 0.1397 0.1397)
			(layers "F.Cu" "F.Mask" "F.Paste")
			(net "GND")
			(options
				(clearance outline)
				(anchor circle)
			)
			(primitives
				(gr_poly
					(pts
						(arc
							(start -0.1778 -0.2794)
							(mid -0.249642 -0.249642)
							(end -0.2794 -0.1778)
						)
						(arc
							(start -0.2794 0.1778)
							(mid -0.249642 0.249642)
							(end -0.1778 0.2794)
						)
						(arc
							(start 0.1778 0.2794)
							(mid 0.249642 0.249642)
							(end 0.2794 0.1778)
						)
						(arc
							(start 0.2794 -0.1778)
							(mid 0.249642 -0.249642)
							(end 0.1778 -0.2794)
						)
					)
					(width 0)
					(fill yes)
				)
			)
		)
	)
	(footprint ""
		(layer "F.Cu")
		(at 95.563436 -244.660674 90)
		(property "Reference" "C55"
			(at 0 0 90)
			(layer "F.SilkS")
			(hide yes)
			(effects
				(font
					(size 1.27 1.27)
				)
			)
		)
		(property "Value" "SCD01U16V1KX-GP"
			(at -2.8321 -1.7399 90)
			(unlocked yes)
			(layer "F.Fab")
			(hide yes)
			(effects
				(font
					(size 1.016 1.016)
					(thickness 0.1524)
				)
			)
		)
		(property "Device Type" "C0201H13"
			(at -2.8321 -3.2639 90)
			(unlocked yes)
			(layer "F.Fab")
			(hide yes)
			(effects
				(font
					(size 1.016 1.016)
					(thickness 0.1524)
				)
			)
		)
		(duplicate_pad_numbers_are_jumpers no)
		(fp_rect
			(start -0.2794 0.6477)
			(end 0.2794 -0.6477)
			(stroke
				(width 0)
				(type default)
			)
			(fill no)
			(layer "F.CrtYd")
		)
		(fp_rect
			(start -0.2794 0.6477)
			(end 0.2794 -0.6477)
			(stroke
				(width 0)
				(type default)
			)
			(fill no)
			(layer "F.Fab")
		)
		(pad "1" smd custom
			(at 0 -0.2794 90)
			(size 0.0762 0.0762)
			(layers "F.Cu" "F.Mask" "F.Paste")
			(net "SAS_HDD_RX_P2")
			(options
				(clearance outline)
				(anchor circle)
			)
			(primitives
				(gr_poly
					(pts
						(arc
							(start 0.1524 -0.127)
							(mid 0.137521 -0.162921)
							(end 0.1016 -0.1778)
						)
						(arc
							(start -0.1016 -0.1778)
							(mid -0.137521 -0.162921)
							(end -0.1524 -0.127)
						)
						(arc
							(start -0.1524 0.127)
							(mid -0.137521 0.162921)
							(end -0.1016 0.1778)
						)
						(arc
							(start 0.1016 0.1778)
							(mid 0.137521 0.162921)
							(end 0.1524 0.127)
						)
					)
					(width 0)
					(fill yes)
				)
			)
		)
		(pad "2" smd custom
			(at 0 0.2794 90)
			(size 0.0762 0.0762)
			(layers "F.Cu" "F.Mask" "F.Paste")
			(net "PHY_SCC_B_TO_DRV_B_2_DP")
			(options
				(clearance outline)
				(anchor circle)
			)
			(primitives
				(gr_poly
					(pts
						(arc
							(start 0.1524 -0.127)
							(mid 0.137521 -0.162921)
							(end 0.1016 -0.1778)
						)
						(arc
							(start -0.1016 -0.1778)
							(mid -0.137521 -0.162921)
							(end -0.1524 -0.127)
						)
						(arc
							(start -0.1524 0.127)
							(mid -0.137521 0.162921)
							(end -0.1016 0.1778)
						)
						(arc
							(start 0.1016 0.1778)
							(mid 0.137521 0.162921)
							(end 0.1524 0.127)
						)
					)
					(width 0)
					(fill yes)
				)
			)
		)
	)
	(footprint ""
		(layer "F.Cu")
		(at 47.173896 -117.74551 -90)
		(property "Reference" "R1126"
			(at 0 0 270)
			(layer "F.SilkS")
			(hide yes)
			(effects
				(font
					(size 1.27 1.27)
				)
			)
		)
		(property "Value" "200KR2F-L-GP"
			(at 0.064008 -3.993896 270)
			(unlocked yes)
			(layer "F.Fab")
			(hide yes)
			(effects
				(font
					(size 1.016 1.016)
					(thickness 0.1524)
				)
			)
		)
		(property "Device Type" "R402H16"
			(at 0.064008 -5.517896 270)
			(unlocked yes)
			(layer "F.Fab")
			(hide yes)
			(effects
				(font
					(size 1.016 1.016)
					(thickness 0.1524)
				)
			)
		)
		(duplicate_pad_numbers_are_jumpers no)
		(fp_line
			(start -0.508 -0.9398)
			(end -0.508 0.9398)
			(stroke
				(width 0.1524)
				(type default)
			)
			(layer "F.SilkS")
		)
		(fp_line
			(start 0.508 -0.9398)
			(end -0.508 -0.9398)
			(stroke
				(width 0.1524)
				(type default)
			)
			(layer "F.SilkS")
		)
		(fp_rect
			(start -0.508 0.9398)
			(end 0.508 -0.9398)
			(stroke
				(width 0)
				(type default)
			)
			(fill no)
			(layer "F.CrtYd")
		)
		(fp_rect
			(start -0.508 0.9398)
			(end 0.508 -0.9398)
			(stroke
				(width 0)
				(type default)
			)
			(fill no)
			(layer "F.Fab")
		)
		(pad "1" smd custom
			(at 0 -0.4445 270)
			(size 0.1397 0.1397)
			(layers "F.Cu" "F.Mask" "F.Paste")
			(net "P5V_B_2_MODE")
			(options
				(clearance outline)
				(anchor circle)
			)
			(primitives
				(gr_poly
					(pts
						(arc
							(start -0.1778 -0.2794)
							(mid -0.249642 -0.249642)
							(end -0.2794 -0.1778)
						)
						(arc
							(start -0.2794 0.1778)
							(mid -0.249642 0.249642)
							(end -0.1778 0.2794)
						)
						(arc
							(start 0.1778 0.2794)
							(mid 0.249642 0.249642)
							(end 0.2794 0.1778)
						)
						(arc
							(start 0.2794 -0.1778)
							(mid 0.249642 -0.249642)
							(end 0.1778 -0.2794)
						)
					)
					(width 0)
					(fill yes)
				)
			)
		)
		(pad "2" smd custom
			(at 0 0.4445 270)
			(size 0.1397 0.1397)
			(layers "F.Cu" "F.Mask" "F.Paste")
			(net "P5V_B_2_PGOOD")
			(options
				(clearance outline)
				(anchor circle)
			)
			(primitives
				(gr_poly
					(pts
						(arc
							(start -0.1778 -0.2794)
							(mid -0.249642 -0.249642)
							(end -0.2794 -0.1778)
						)
						(arc
							(start -0.2794 0.1778)
							(mid -0.249642 0.249642)
							(end -0.1778 0.2794)
						)
						(arc
							(start 0.1778 0.2794)
							(mid 0.249642 0.249642)
							(end 0.2794 0.1778)
						)
						(arc
							(start 0.2794 -0.1778)
							(mid 0.249642 -0.249642)
							(end 0.1778 -0.2794)
						)
					)
					(width 0)
					(fill yes)
				)
			)
		)
	)
)
